# TIMECARD (Time Appliance Project (Time Card)) — schematic netlist excerpt (pin names and nets, part order shuffled) for the footprints in the layout excerpt that follows; sources: Cadence DE-HDL packaged netlist, KiCad conversion of R4006-B0001-02_R01.brd

CR6  DIODE_4_V1  pkg SOT143  page 10
  GND  = SG
  IO1  = FT4232_FPGA_TMS
  IO2  = FT4232_FPGA_TDI
  VDD  = NC

(kicad_pcb
	(version 20260206)
	(generator "pcbnew")
	(generator_version "10.0")
	(general
		(thickness 1.6)
		(legacy_teardrops no)
	)
	(paper "A4")
	(title_block
		(title "timecard-production-celestica-r4006 — R4006-B0001-02_R01.brd")
		(comment 1 "Time Appliance Project (Time Card) / footprints 713-713 of 1113")
	)
	(layers
		(0 "F.Cu" signal "TOP")
		(4 "In1.Cu" signal "L02_GND1")
		(6 "In2.Cu" signal "L03_SIG1")
		(8 "In3.Cu" signal "L04_GND2")
		(10 "In4.Cu" signal "L05_VCC1")
		(12 "In5.Cu" signal "L06_VCC2")
		(14 "In6.Cu" signal "L07_GND3")
		(16 "In7.Cu" signal "L08_SIG2")
		(18 "In8.Cu" signal "L09_GND4")
		(2 "B.Cu" signal "BOTTOM")
		(9 "F.Adhes" user "F.Adhesive")
		(11 "B.Adhes" user "B.Adhesive")
		(13 "F.Paste" user "Package Geometry/Pastemask Top")
		(15 "B.Paste" user "Package Geometry/Pastemask Bottom")
		(5 "F.SilkS" user "Ref Des/Silkscreen Top")
		(7 "B.SilkS" user "Ref Des/Silkscreen Bottom")
		(1 "F.Mask" user "Board Geometry/Soldermask Top")
		(3 "B.Mask" user "Board Geometry/Soldermask Bottom")
		(17 "Dwgs.User" user "User.Drawings")
		(19 "Cmts.User" user "User.Comments")
		(21 "Eco1.User" user "User.Eco1")
		(23 "Eco2.User" user "User.Eco2")
		(25 "Edge.Cuts" user "Board Geometry/Outline")
		(27 "Margin" user)
		(31 "F.CrtYd" user "Package Geometry/Place Bound Top")
		(29 "B.CrtYd" user "Package Geometry/Place Bound Bottom")
		(35 "F.Fab" user "Ref Des/Assembly Top")
		(33 "B.Fab" user "Ref Des/Assembly Bottom")
	)
	(footprint ""
		(layer "B.Cu")
		(at 144.9832 -75.3364 -90)
		(property "Reference" "CR6"
			(at 1.1684 -3.44043 270)
			(unlocked yes)
			(layer "B.SilkS")
			(effects
				(font
					(size 0.7874 0.5842)
					(thickness 0.1524)
				)
				(justify mirror)
			)
		)
		(property "Value" ""
			(at 0 0 90)
			(layer "B.Fab")
			(effects
				(font
					(size 1.27 1.27)
				)
				(justify mirror)
			)
		)
		(property "User Part Number" "PARTNUM*"
			(at -0.254 3.718306 270)
			(unlocked yes)
			(layer "Cmts.User")
			(hide yes)
			(effects
				(font
					(size 0.7874 0.5842)
					(thickness 0.1524)
				)
				(justify mirror)
			)
		)
		(property "Device Type" "DIODE_4_V1-G122-10123-01"
			(at -0.254 2.702306 270)
			(unlocked yes)
			(layer "B.Fab")
			(hide yes)
			(effects
				(font
					(size 0.7874 0.5842)
					(thickness 0.1524)
				)
				(justify mirror)
			)
		)
		(duplicate_pad_numbers_are_jumpers no)
		(fp_line
			(start -2.0828 1.7018)
			(end 2.0828 1.7018)
			(stroke
				(width 0.1)
				(type default)
			)
			(layer "B.SilkS")
		)
		(fp_line
			(start 2.0828 1.7018)
			(end 2.0828 -1.7018)
			(stroke
				(width 0.1)
				(type default)
			)
			(layer "B.SilkS")
		)
		(fp_line
			(start -2.0828 -1.7018)
			(end -2.0828 1.7018)
			(stroke
				(width 0.1)
				(type default)
			)
			(layer "B.SilkS")
		)
		(fp_line
			(start 2.0828 -1.7018)
			(end -2.0828 -1.7018)
			(stroke
				(width 0.1)
				(type default)
			)
			(layer "B.SilkS")
		)
		(fp_poly
			(pts
				(arc
					(start 2.6162 -1.27)
					(mid 2.6162 -0.508)
					(end 2.6162 -1.27)
				)
			)
			(stroke
				(width 0)
				(type default)
			)
			(fill yes)
			(layer "B.SilkS")
		)
		(fp_rect
			(start -2.3368 1.9304)
			(end 2.3368 -1.9304)
			(stroke
				(width 0)
				(type default)
			)
			(fill no)
			(layer "B.CrtYd")
		)
		(fp_line
			(start -0.6477 1.42875)
			(end 0.6477 1.42875)
			(stroke
				(width 0.1)
				(type default)
			)
			(layer "B.Fab")
		)
		(fp_line
			(start 0.6477 1.42875)
			(end 0.6477 -1.42875)
			(stroke
				(width 0.1)
				(type default)
			)
			(layer "B.Fab")
		)
		(fp_line
			(start -1.143 1.1811)
			(end -0.6477 1.1811)
			(stroke
				(width 0.1)
				(type default)
			)
			(layer "B.Fab")
		)
		(fp_line
			(start -0.6477 1.1811)
			(end -0.6477 0.7239)
			(stroke
				(width 0.1)
				(type default)
			)
			(layer "B.Fab")
		)
		(fp_line
			(start 0.6477 1.1811)
			(end 1.143 1.1811)
			(stroke
				(width 0.1)
				(type default)
			)
			(layer "B.Fab")
		)
		(fp_line
			(start 1.143 1.1811)
			(end 1.143 0.7239)
			(stroke
				(width 0.1)
				(type default)
			)
			(layer "B.Fab")
		)
		(fp_line
			(start -1.143 0.7239)
			(end -1.143 1.1811)
			(stroke
				(width 0.1)
				(type default)
			)
			(layer "B.Fab")
		)
		(fp_line
			(start -0.6477 0.7239)
			(end -1.143 0.7239)
			(stroke
				(width 0.1)
				(type default)
			)
			(layer "B.Fab")
		)
		(fp_line
			(start 0.6477 0.7239)
			(end 0.6477 1.1811)
			(stroke
				(width 0.1)
				(type default)
			)
			(layer "B.Fab")
		)
		(fp_line
			(start 1.143 0.7239)
			(end 0.6477 0.7239)
			(stroke
				(width 0.1)
				(type default)
			)
			(layer "B.Fab")
		)
		(fp_line
			(start 0.6477 -0.3175)
			(end 1.143 -0.3175)
			(stroke
				(width 0.1)
				(type default)
			)
			(layer "B.Fab")
		)
		(fp_line
			(start 1.143 -0.3175)
			(end 1.143 -1.1811)
			(stroke
				(width 0.1)
				(type default)
			)
			(layer "B.Fab")
		)
		(fp_line
			(start -1.143 -0.7239)
			(end -0.6477 -0.7239)
			(stroke
				(width 0.1)
				(type default)
			)
			(layer "B.Fab")
		)
		(fp_line
			(start -0.6477 -0.7239)
			(end -0.6477 -1.1811)
			(stroke
				(width 0.1)
				(type default)
			)
			(layer "B.Fab")
		)
		(fp_line
			(start -1.143 -1.1811)
			(end -1.143 -0.7239)
			(stroke
				(width 0.1)
				(type default)
			)
			(layer "B.Fab")
		)
		(fp_line
			(start -0.6477 -1.1811)
			(end -1.143 -1.1811)
			(stroke
				(width 0.1)
				(type default)
			)
			(layer "B.Fab")
		)
		(fp_line
			(start 0.6477 -1.1811)
			(end 0.6477 -0.3175)
			(stroke
				(width 0.1)
				(type default)
			)
			(layer "B.Fab")
		)
		(fp_line
			(start 1.143 -1.1811)
			(end 0.6477 -1.1811)
			(stroke
				(width 0.1)
				(type default)
			)
			(layer "B.Fab")
		)
		(fp_line
			(start -0.6477 -1.42875)
			(end -0.6477 1.42875)
			(stroke
				(width 0.1)
				(type default)
			)
			(layer "B.Fab")
		)
		(fp_line
			(start 0.6477 -1.42875)
			(end -0.6477 -1.42875)
			(stroke
				(width 0.1)
				(type default)
			)
			(layer "B.Fab")
		)
		(fp_poly
			(pts
				(arc
					(start 0.381 -0.9398)
					(mid 0.381 -0.5588)
					(end 0.381 -0.9398)
				)
			)
			(stroke
				(width 0)
				(type default)
			)
			(fill yes)
			(layer "B.Fab")
		)
		(fp_text user "3"
			(at -2.72923 1.0541 0)
			(unlocked yes)
			(layer "B.SilkS")
			(effects
				(font
					(size 0.7874 0.5842)
					(thickness 0.1524)
				)
				(justify left mirror)
			)
		)
		(fp_text user "2"
			(at 2.85877 0.9271 0)
			(unlocked yes)
			(layer "B.SilkS")
			(effects
				(font
					(size 0.7874 0.5842)
					(thickness 0.1524)
				)
				(justify left mirror)
			)
		)
		(fp_text user "4"
			(at -2.72923 -1.7399 0)
			(unlocked yes)
			(layer "B.SilkS")
			(effects
				(font
					(size 0.7874 0.5842)
					(thickness 0.1524)
				)
				(justify left mirror)
			)
		)
		(fp_text user "2"
			(at 2.08407 0.7112 0)
			(unlocked yes)
			(layer "B.Fab")
			(effects
				(font
					(size 0.7874 0.5842)
					(thickness 0.1524)
				)
				(justify left mirror)
			)
		)
		(fp_text user "3"
			(at -1.89103 0.669036 0)
			(unlocked yes)
			(layer "B.Fab")
			(effects
				(font
					(size 0.7874 0.5842)
					(thickness 0.1524)
				)
				(justify left mirror)
			)
		)
		(fp_text user "4"
			(at -1.91643 -1.261618 0)
			(unlocked yes)
			(layer "B.Fab")
			(effects
				(font
					(size 0.7874 0.5842)
					(thickness 0.1524)
				)
				(justify left mirror)
			)
		)
		(pad "1" smd rect
			(at 1.1049 -0.7493 90)
			(size 1.4478 1.0922)
			(layers "B.Cu" "B.Mask" "B.Paste")
			(net "SG")
		)
		(pad "2" smd rect
			(at 1.1049 0.9525 90)
			(size 1.4478 0.9906)
			(layers "B.Cu" "B.Mask" "B.Paste")
			(net "FT4232_FPGA_TMS")
		)
		(pad "3" smd rect
			(at -1.1049 0.9525 90)
			(size 1.4478 0.9906)
			(layers "B.Cu" "B.Mask" "B.Paste")
			(net "FT4232_FPGA_TDI")
		)
		(pad "4" smd rect
			(at -1.1049 -0.9525 90)
			(size 1.4478 0.9906)
			(layers "B.Cu" "B.Mask" "B.Paste")
			(net "Net_623")
		)
		(zone
			(layer "B.Cu")
			(hatch none 0.5)
			(connect_pads
				(clearance 0)
			)
			(min_thickness 0.25)
			(keepout
				(tracks allowed)
				(vias not_allowed)
				(pads allowed)
				(copperpour not_allowed)
				(footprints allowed)
			)
			(placement
				(enabled no)
				(sheetname "")
			)
			(fill
				(thermal_gap 0.5)
				(thermal_bridge_width 0.5)
				(island_removal_mode 0)
			)
			(polygon
				(pts
					(xy 146.2786 -74.6887) (xy 146.4183 -74.6887) (xy 146.4183 -75.7174) (xy 145.4404 -75.7174) (xy 145.4404 -75.9841)
					(xy 144.526 -75.9841) (xy 144.526 -75.7174) (xy 143.5481 -75.7174) (xy 143.5481 -74.9554) (xy 144.526 -74.9554)
					(xy 144.526 -74.6887) (xy 145.1864 -74.6887) (xy 145.1864 -74.9554) (xy 146.2786 -74.9554)
				)
			)
		)
	)
)
